(kicad_pcb
	(version 20260206)
	(generator "pcbnew")
	(generator_version "10.0")
	(general
		(thickness 1.6)
		(legacy_teardrops no)
	)
	(paper "A4")
	(title_block
		(title "Bryce Canyon_IOM_IOC_16318-2_OCP.brd")
		(comment 1 "Bryce Canyon / footprints 338-344 of 1605")
	)
	(layers
		(0 "F.Cu" signal "TOP")
		(4 "In1.Cu" signal "L2GND")
		(6 "In2.Cu" signal "L3")
		(8 "In3.Cu" signal "L4VCC")
		(10 "In4.Cu" signal "L5VCC")
		(12 "In5.Cu" signal "L6")
		(14 "In6.Cu" signal "L7GND")
		(2 "B.Cu" signal "BOTTOM")
		(9 "F.Adhes" user "F.Adhesive")
		(11 "B.Adhes" user "B.Adhesive")
		(13 "F.Paste" user "Package Geometry/Pastemask Top")
		(15 "B.Paste" user "Package Geometry/Pastemask Bottom")
		(5 "F.SilkS" user "Ref Des/Silkscreen Top")
		(7 "B.SilkS" user "Ref Des/Silkscreen Bottom")
		(1 "F.Mask" user "Board Geometry/Soldermask Top")
		(3 "B.Mask" user "Board Geometry/Soldermask Bottom")
		(17 "Dwgs.User" user "User.Drawings")
		(19 "Cmts.User" user "User.Comments")
		(21 "Eco1.User" user "User.Eco1")
		(23 "Eco2.User" user "User.Eco2")
		(25 "Edge.Cuts" user "Board Geometry/Outline")
		(27 "Margin" user)
		(31 "F.CrtYd" user "Package Geometry/Place Bound Top")
		(29 "B.CrtYd" user "Package Geometry/Place Bound Bottom")
		(35 "F.Fab" user "Ref Des/Assembly Top")
		(33 "B.Fab" user "Ref Des/Assembly Bottom")
	)
	(footprint ""
		(layer "F.Cu")
		(at 72.04964 -165.6334 90)
		(property "Reference" "R542"
			(at 0 0 90)
			(layer "F.SilkS")
			(hide yes)
			(effects
				(font
					(size 1.27 1.27)
				)
			)
		)
		(property "Value" "0R2J-2-GP"
			(at 0.064008 -3.993896 90)
			(unlocked yes)
			(layer "F.Fab")
			(hide yes)
			(effects
				(font
					(size 1.016 1.016)
					(thickness 0.1524)
				)
			)
		)
		(property "Device Type" "R402H16"
			(at 0.064008 -5.517896 90)
			(unlocked yes)
			(layer "F.Fab")
			(hide yes)
			(effects
				(font
					(size 1.016 1.016)
					(thickness 0.1524)
				)
			)
		)
		(duplicate_pad_numbers_are_jumpers no)
		(fp_line
			(start 0.508 -0.9398)
			(end -0.508 -0.9398)
			(stroke
				(width 0.1524)
				(type default)
			)
			(layer "F.SilkS")
		)
		(fp_line
			(start -0.508 -0.9398)
			(end -0.508 0.9398)
			(stroke
				(width 0.1524)
				(type default)
			)
			(layer "F.SilkS")
		)
		(fp_rect
			(start -0.508 0.9398)
			(end 0.508 -0.9398)
			(stroke
				(width 0)
				(type default)
			)
			(fill no)
			(layer "F.CrtYd")
		)
		(fp_rect
			(start -0.508 0.9398)
			(end 0.508 -0.9398)
			(stroke
				(width 0)
				(type default)
			)
			(fill no)
			(layer "F.Fab")
		)
		(pad "1" smd custom
			(at 0 -0.4445 90)
			(size 0.1397 0.1397)
			(layers "F.Cu" "F.Mask" "F.Paste")
			(net "PWRGD_P1V2_STBY")
			(options
				(clearance outline)
				(anchor circle)
			)
			(primitives
				(gr_poly
					(pts
						(arc
							(start -0.1778 -0.2794)
							(mid -0.249642 -0.249642)
							(end -0.2794 -0.1778)
						)
						(arc
							(start -0.2794 0.1778)
							(mid -0.249642 0.249642)
							(end -0.1778 0.2794)
						)
						(arc
							(start 0.1778 0.2794)
							(mid 0.249642 0.249642)
							(end 0.2794 0.1778)
						)
						(arc
							(start 0.2794 -0.1778)
							(mid 0.249642 -0.249642)
							(end 0.1778 -0.2794)
						)
					)
					(width 0)
					(fill yes)
				)
			)
		)
		(pad "2" smd custom
			(at 0 0.4445 90)
			(size 0.1397 0.1397)
			(layers "F.Cu" "F.Mask" "F.Paste")
			(net "TPS74801_P1V15_STBY_EN")
			(options
				(clearance outline)
				(anchor circle)
			)
			(primitives
				(gr_poly
					(pts
						(arc
							(start -0.1778 -0.2794)
							(mid -0.249642 -0.249642)
							(end -0.2794 -0.1778)
						)
						(arc
							(start -0.2794 0.1778)
							(mid -0.249642 0.249642)
							(end -0.1778 0.2794)
						)
						(arc
							(start 0.1778 0.2794)
							(mid 0.249642 0.249642)
							(end 0.2794 0.1778)
						)
						(arc
							(start 0.2794 -0.1778)
							(mid 0.249642 -0.249642)
							(end 0.1778 -0.2794)
						)
					)
					(width 0)
					(fill yes)
				)
			)
		)
	)
	(footprint ""
		(layer "F.Cu")
		(at 133.48208 -17.90446)
		(property "Reference" "D1"
			(at 0 0 0)
			(layer "F.SilkS")
			(hide yes)
			(effects
				(font
					(size 1.27 1.27)
				)
			)
		)
		(property "Value" "SMF15A-GP"
			(at -2.0955 1.2192 0)
			(unlocked yes)
			(layer "F.Fab")
			(hide yes)
			(effects
				(font
					(size 1.016 1.016)
					(thickness 0.1524)
				)
			)
		)
		(property "Device Type" "SOD123AK-2H43"
			(at -2.0955 -0.3048 0)
			(unlocked yes)
			(layer "F.Fab")
			(hide yes)
			(effects
				(font
					(size 1.016 1.016)
					(thickness 0.1524)
				)
			)
		)
		(duplicate_pad_numbers_are_jumpers no)
		(fp_line
			(start -1.1557 -2.7686)
			(end -1.1557 2.7686)
			(stroke
				(width 0.1524)
				(type default)
			)
			(layer "F.SilkS")
		)
		(fp_line
			(start -1.1557 2.7686)
			(end 1.1557 2.7686)
			(stroke
				(width 0.1524)
				(type default)
			)
			(layer "F.SilkS")
		)
		(fp_line
			(start 1.1557 -2.7686)
			(end -1.1557 -2.7686)
			(stroke
				(width 0.1524)
				(type default)
			)
			(layer "F.SilkS")
		)
		(fp_line
			(start 1.1557 2.7686)
			(end 1.1557 -2.7686)
			(stroke
				(width 0.1524)
				(type default)
			)
			(layer "F.SilkS")
		)
		(fp_line
			(start 1.1557 2.921)
			(end -1.1557 2.921)
			(stroke
				(width 0.508)
				(type default)
			)
			(layer "F.SilkS")
		)
		(fp_poly
			(pts
				(xy -0.4572 1.8669) (xy -0.4572 1.397) (xy -0.9017 1.397) (xy -0.9017 -1.397) (xy -0.4572 -1.397)
				(xy -0.4572 -1.8669) (xy 0.4572 -1.8669) (xy 0.4572 -1.397) (xy 0.9017 -1.397) (xy 0.9017 1.397)
				(xy 0.4572 1.397) (xy 0.4572 1.8669)
			)
			(stroke
				(width 0)
				(type default)
			)
			(fill no)
			(layer "F.CrtYd")
		)
		(fp_poly
			(pts
				(xy -1.4097 2.8448) (xy -1.4097 -2.8448) (xy 1.4097 -2.8448) (xy 1.4097 1.3716) (xy 0.9017 1.3716)
				(xy 0.9017 -1.397) (xy 0.4572 -1.397) (xy 0.4572 -1.8669) (xy -0.4572 -1.8669) (xy -0.4572 -1.397)
				(xy -0.9017 -1.397) (xy -0.9017 1.397) (xy -0.4572 1.397) (xy -0.4572 1.8669) (xy 0.4572 1.8669)
				(xy 0.4572 1.397) (xy 0.9017 1.397) (xy 0.9017 1.3843) (xy 1.4097 1.3843) (xy 1.4097 2.8448)
			)
			(stroke
				(width 0)
				(type default)
			)
			(fill no)
			(layer "F.CrtYd")
		)
		(fp_rect
			(start -1.4097 2.8448)
			(end 1.4097 -2.8448)
			(stroke
				(width 0)
				(type default)
			)
			(fill no)
			(layer "F.Fab")
		)
		(pad "A" smd rect
			(at 0 -1.75768)
			(size 1.143 1.4986)
			(layers "F.Cu" "F.Mask" "F.Paste")
			(net "GND")
		)
		(pad "K" smd rect
			(at 0 1.75768)
			(size 1.143 1.4986)
			(layers "F.Cu" "F.Mask" "F.Paste")
			(net "P12V_IOM")
		)
	)
	(footprint ""
		(layer "F.Cu")
		(at 40.220646 -179.12461 180)
		(property "Reference" "R487"
			(at 0 0 180)
			(layer "F.SilkS")
			(hide yes)
			(effects
				(font
					(size 1.27 1.27)
				)
			)
		)
		(property "Value" "10KR2F-2-GP"
			(at 0.064008 -3.993896 180)
			(unlocked yes)
			(layer "F.Fab")
			(hide yes)
			(effects
				(font
					(size 1.016 1.016)
					(thickness 0.1524)
				)
			)
		)
		(property "Device Type" "R402H16"
			(at 0.064008 -5.517896 180)
			(unlocked yes)
			(layer "F.Fab")
			(hide yes)
			(effects
				(font
					(size 1.016 1.016)
					(thickness 0.1524)
				)
			)
		)
		(duplicate_pad_numbers_are_jumpers no)
		(fp_line
			(start 0.508 -0.9398)
			(end -0.508 -0.9398)
			(stroke
				(width 0.1524)
				(type default)
			)
			(layer "F.SilkS")
		)
		(fp_line
			(start -0.508 -0.9398)
			(end -0.508 0.9398)
			(stroke
				(width 0.1524)
				(type default)
			)
			(layer "F.SilkS")
		)
		(fp_rect
			(start -0.508 0.9398)
			(end 0.508 -0.9398)
			(stroke
				(width 0)
				(type default)
			)
			(fill no)
			(layer "F.CrtYd")
		)
		(fp_rect
			(start -0.508 0.9398)
			(end 0.508 -0.9398)
			(stroke
				(width 0)
				(type default)
			)
			(fill no)
			(layer "F.Fab")
		)
		(pad "1" smd custom
			(at 0 -0.4445 180)
			(size 0.1397 0.1397)
			(layers "F.Cu" "F.Mask" "F.Paste")
			(net "P3V3_STBY_VREG")
			(options
				(clearance outline)
				(anchor circle)
			)
			(primitives
				(gr_poly
					(pts
						(arc
							(start -0.1778 -0.2794)
							(mid -0.249642 -0.249642)
							(end -0.2794 -0.1778)
						)
						(arc
							(start -0.2794 0.1778)
							(mid -0.249642 0.249642)
							(end -0.1778 0.2794)
						)
						(arc
							(start 0.1778 0.2794)
							(mid 0.249642 0.249642)
							(end 0.2794 0.1778)
						)
						(arc
							(start 0.2794 -0.1778)
							(mid 0.249642 -0.249642)
							(end 0.1778 -0.2794)
						)
					)
					(width 0)
					(fill yes)
				)
			)
		)
		(pad "2" smd custom
			(at 0 0.4445 180)
			(size 0.1397 0.1397)
			(layers "F.Cu" "F.Mask" "F.Paste")
			(net "PWRGD_P3V3_STBY")
			(options
				(clearance outline)
				(anchor circle)
			)
			(primitives
				(gr_poly
					(pts
						(arc
							(start -0.1778 -0.2794)
							(mid -0.249642 -0.249642)
							(end -0.2794 -0.1778)
						)
						(arc
							(start -0.2794 0.1778)
							(mid -0.249642 0.249642)
							(end -0.1778 0.2794)
						)
						(arc
							(start 0.1778 0.2794)
							(mid 0.249642 0.249642)
							(end 0.2794 0.1778)
						)
						(arc
							(start 0.2794 -0.1778)
							(mid 0.249642 -0.249642)
							(end 0.1778 -0.2794)
						)
					)
					(width 0)
					(fill yes)
				)
			)
		)
	)
	(footprint ""
		(layer "F.Cu")
		(at 219.691712 -98.448368)
		(property "Reference" "C373"
			(at 0 0 0)
			(layer "F.SilkS")
			(hide yes)
			(effects
				(font
					(size 1.27 1.27)
				)
			)
		)
		(property "Value" "SC100U6D3V6MX-GP"
			(at -0.0762 -5.1308 0)
			(unlocked yes)
			(layer "F.Fab")
			(hide yes)
			(effects
				(font
					(size 1.016 1.016)
					(thickness 0.1524)
				)
			)
		)
		(property "Device Type" "C1206H71"
			(at -0.127 -6.6548 0)
			(unlocked yes)
			(layer "F.Fab")
			(hide yes)
			(effects
				(font
					(size 1.016 1.016)
					(thickness 0.1524)
				)
			)
		)
		(duplicate_pad_numbers_are_jumpers no)
		(fp_line
			(start -1.016 -2.2352)
			(end 1.016 -2.2352)
			(stroke
				(width 0.1524)
				(type default)
			)
			(layer "F.SilkS")
		)
		(fp_line
			(start -1.016 -0.8382)
			(end -1.016 -2.2352)
			(stroke
				(width 0.1524)
				(type default)
			)
			(layer "F.SilkS")
		)
		(fp_line
			(start -1.016 2.2352)
			(end -1.016 0.8382)
			(stroke
				(width 0.1524)
				(type default)
			)
			(layer "F.SilkS")
		)
		(fp_line
			(start 1.016 -2.2352)
			(end 1.016 -0.8382)
			(stroke
				(width 0.1524)
				(type default)
			)
			(layer "F.SilkS")
		)
		(fp_line
			(start 1.016 0.8382)
			(end 1.016 2.2352)
			(stroke
				(width 0.1524)
				(type default)
			)
			(layer "F.SilkS")
		)
		(fp_line
			(start 1.016 2.2352)
			(end -1.016 2.2352)
			(stroke
				(width 0.1524)
				(type default)
			)
			(layer "F.SilkS")
		)
		(fp_rect
			(start -1.0922 2.3114)
			(end 1.0922 -2.3114)
			(stroke
				(width 0)
				(type default)
			)
			(fill no)
			(layer "F.CrtYd")
		)
		(fp_poly
			(pts
				(xy 1.0922 -2.3114) (xy 1.0922 2.3114) (xy -1.0922 2.3114) (xy -1.0922 -2.3114)
			)
			(stroke
				(width 0)
				(type default)
			)
			(fill no)
			(layer "F.Fab")
		)
		(pad "1" smd rect
			(at 0 -1.397)
			(size 1.651 1.27)
			(layers "F.Cu" "F.Mask" "F.Paste")
			(net "GND")
		)
		(pad "2" smd rect
			(at 0 1.397)
			(size 1.651 1.27)
			(layers "F.Cu" "F.Mask" "F.Paste")
			(net "SAS0_AVDD")
		)
	)
	(footprint ""
		(layer "F.Cu")
		(at 160.64484 -40.40632 180)
		(property "Reference" "C527"
			(at 0 0 180)
			(layer "F.SilkS")
			(hide yes)
			(effects
				(font
					(size 1.27 1.27)
				)
			)
		)
		(property "Value" "SC1000P2KV6KX-GP-U"
			(at 0.0508 -3.5052 180)
			(unlocked yes)
			(layer "F.Fab")
			(hide yes)
			(effects
				(font
					(size 1.016 1.016)
					(thickness 0.1524)
				)
			)
		)
		(property "Device Type" "C1206H58"
			(at 0.0508 -5.0292 180)
			(unlocked yes)
			(layer "F.Fab")
			(hide yes)
			(effects
				(font
					(size 1.016 1.016)
					(thickness 0.1524)
				)
			)
		)
		(duplicate_pad_numbers_are_jumpers no)
		(fp_line
			(start 1.016 2.2352)
			(end -1.016 2.2352)
			(stroke
				(width 0.1524)
				(type default)
			)
			(layer "F.SilkS")
		)
		(fp_line
			(start 1.016 0.8382)
			(end 1.016 2.2352)
			(stroke
				(width 0.1524)
				(type default)
			)
			(layer "F.SilkS")
		)
		(fp_line
			(start 1.016 -2.2352)
			(end 1.016 -0.8382)
			(stroke
				(width 0.1524)
				(type default)
			)
			(layer "F.SilkS")
		)
		(fp_line
			(start 1.016 -2.2352)
			(end -1.016 -2.2352)
			(stroke
				(width 0.1524)
				(type default)
			)
			(layer "F.SilkS")
		)
		(fp_line
			(start -1.016 2.2352)
			(end -1.016 0.8128)
			(stroke
				(width 0.1524)
				(type default)
			)
			(layer "F.SilkS")
		)
		(fp_line
			(start -1.016 -2.2352)
			(end -1.016 -0.8382)
			(stroke
				(width 0.1524)
				(type default)
			)
			(layer "F.SilkS")
		)
		(fp_rect
			(start -1.0922 2.3114)
			(end 1.0922 -2.3114)
			(stroke
				(width 0)
				(type default)
			)
			(fill no)
			(layer "F.CrtYd")
		)
		(fp_poly
			(pts
				(xy -1.0922 -2.3114) (xy 1.0922 -2.3114) (xy 1.0922 2.3114) (xy -1.0922 2.3114)
			)
			(stroke
				(width 0)
				(type default)
			)
			(fill no)
			(layer "F.Fab")
		)
		(pad "1" smd rect
			(at 0 -1.397 180)
			(size 1.651 1.27)
			(layers "F.Cu" "F.Mask" "F.Paste")
			(net "EXT2_CONN_GND")
		)
		(pad "2" smd rect
			(at 0 1.397 180)
			(size 1.651 1.27)
			(layers "F.Cu" "F.Mask" "F.Paste")
			(net "GND")
		)
	)
	(footprint ""
		(layer "F.Cu")
		(at 99.380548 -17.925034 180)
		(property "Reference" "R38"
			(at 0 0 180)
			(layer "F.SilkS")
			(hide yes)
			(effects
				(font
					(size 1.27 1.27)
				)
			)
		)
		(property "Value" "0R2J-2-GP"
			(at 0.064008 -3.993896 180)
			(unlocked yes)
			(layer "F.Fab")
			(hide yes)
			(effects
				(font
					(size 1.016 1.016)
					(thickness 0.1524)
				)
			)
		)
		(property "Device Type" "R402H16"
			(at 0.064008 -5.517896 180)
			(unlocked yes)
			(layer "F.Fab")
			(hide yes)
			(effects
				(font
					(size 1.016 1.016)
					(thickness 0.1524)
				)
			)
		)
		(duplicate_pad_numbers_are_jumpers no)
		(fp_line
			(start 0.508 -0.9398)
			(end -0.508 -0.9398)
			(stroke
				(width 0.1524)
				(type default)
			)
			(layer "F.SilkS")
		)
		(fp_line
			(start -0.508 -0.9398)
			(end -0.508 0.9398)
			(stroke
				(width 0.1524)
				(type default)
			)
			(layer "F.SilkS")
		)
		(fp_rect
			(start -0.508 0.9398)
			(end 0.508 -0.9398)
			(stroke
				(width 0)
				(type default)
			)
			(fill no)
			(layer "F.CrtYd")
		)
		(fp_rect
			(start -0.508 0.9398)
			(end 0.508 -0.9398)
			(stroke
				(width 0)
				(type default)
			)
			(fill no)
			(layer "F.Fab")
		)
		(pad "1" smd custom
			(at 0 -0.4445 180)
			(size 0.1397 0.1397)
			(layers "F.Cu" "F.Mask" "F.Paste")
			(net "USB_P1_F_DP1")
			(options
				(clearance outline)
				(anchor circle)
			)
			(primitives
				(gr_poly
					(pts
						(arc
							(start -0.1778 -0.2794)
							(mid -0.249642 -0.249642)
							(end -0.2794 -0.1778)
						)
						(arc
							(start -0.2794 0.1778)
							(mid -0.249642 0.249642)
							(end -0.1778 0.2794)
						)
						(arc
							(start 0.1778 0.2794)
							(mid 0.249642 0.249642)
							(end 0.2794 0.1778)
						)
						(arc
							(start 0.2794 -0.1778)
							(mid 0.249642 -0.249642)
							(end 0.1778 -0.2794)
						)
					)
					(width 0)
					(fill yes)
				)
			)
		)
		(pad "2" smd custom
			(at 0 0.4445 180)
			(size 0.1397 0.1397)
			(layers "F.Cu" "F.Mask" "F.Paste")
			(net "USB_P1_DP")
			(options
				(clearance outline)
				(anchor circle)
			)
			(primitives
				(gr_poly
					(pts
						(arc
							(start -0.1778 -0.2794)
							(mid -0.249642 -0.249642)
							(end -0.2794 -0.1778)
						)
						(arc
							(start -0.2794 0.1778)
							(mid -0.249642 0.249642)
							(end -0.1778 0.2794)
						)
						(arc
							(start 0.1778 0.2794)
							(mid 0.249642 0.249642)
							(end 0.2794 0.1778)
						)
						(arc
							(start 0.2794 -0.1778)
							(mid 0.249642 -0.249642)
							(end 0.1778 -0.2794)
						)
					)
					(width 0)
					(fill yes)
				)
			)
		)
	)
	(footprint ""
		(layer "F.Cu")
		(at 38.544246 -177.14341)
		(property "Reference" "R486"
			(at 0 0 0)
			(layer "F.SilkS")
			(hide yes)
			(effects
				(font
					(size 1.27 1.27)
				)
			)
		)
		(property "Value" "3K83R2F-GP"
			(at 0.064008 -3.993896 0)
			(unlocked yes)
			(layer "F.Fab")
			(hide yes)
			(effects
				(font
					(size 1.016 1.016)
					(thickness 0.1524)
				)
			)
		)
		(property "Device Type" "R402H16"
			(at 0.064008 -5.517896 0)
			(unlocked yes)
			(layer "F.Fab")
			(hide yes)
			(effects
				(font
					(size 1.016 1.016)
					(thickness 0.1524)
				)
			)
		)
		(duplicate_pad_numbers_are_jumpers no)
		(fp_line
			(start -0.508 -0.9398)
			(end -0.508 0.9398)
			(stroke
				(width 0.1524)
				(type default)
			)
			(layer "F.SilkS")
		)
		(fp_line
			(start 0.508 -0.9398)
			(end -0.508 -0.9398)
			(stroke
				(width 0.1524)
				(type default)
			)
			(layer "F.SilkS")
		)
		(fp_rect
			(start -0.508 0.9398)
			(end 0.508 -0.9398)
			(stroke
				(width 0)
				(type default)
			)
			(fill no)
			(layer "F.CrtYd")
		)
		(fp_rect
			(start -0.508 0.9398)
			(end 0.508 -0.9398)
			(stroke
				(width 0)
				(type default)
			)
			(fill no)
			(layer "F.Fab")
		)
		(pad "1" smd custom
			(at 0 -0.4445)
			(size 0.1397 0.1397)
			(layers "F.Cu" "F.Mask" "F.Paste")
			(net "P3V3_STBY_EN")
			(options
				(clearance outline)
				(anchor circle)
			)
			(primitives
				(gr_poly
					(pts
						(arc
							(start -0.1778 -0.2794)
							(mid -0.249642 -0.249642)
							(end -0.2794 -0.1778)
						)
						(arc
							(start -0.2794 0.1778)
							(mid -0.249642 0.249642)
							(end -0.1778 0.2794)
						)
						(arc
							(start 0.1778 0.2794)
							(mid 0.249642 0.249642)
							(end 0.2794 0.1778)
						)
						(arc
							(start 0.2794 -0.1778)
							(mid 0.249642 -0.249642)
							(end 0.1778 -0.2794)
						)
					)
					(width 0)
					(fill yes)
				)
			)
		)
		(pad "2" smd custom
			(at 0 0.4445)
			(size 0.1397 0.1397)
			(layers "F.Cu" "F.Mask" "F.Paste")
			(net "GND")
			(options
				(clearance outline)
				(anchor circle)
			)
			(primitives
				(gr_poly
					(pts
						(arc
							(start -0.1778 -0.2794)
							(mid -0.249642 -0.249642)
							(end -0.2794 -0.1778)
						)
						(arc
							(start -0.2794 0.1778)
							(mid -0.249642 0.249642)
							(end -0.1778 0.2794)
						)
						(arc
							(start 0.1778 0.2794)
							(mid 0.249642 0.249642)
							(end 0.2794 0.1778)
						)
						(arc
							(start 0.2794 -0.1778)
							(mid 0.249642 -0.249642)
							(end 0.1778 -0.2794)
						)
					)
					(width 0)
					(fill yes)
				)
			)
		)
	)
)
